G04 ================== begin FILE IDENTIFICATION RECORD ==================*
G04 Layout Name:  D:/<user>/Wistron_project/16315-1/gbr/16315-1.brd*
G04 Film Name:    SE_REF_L12*
G04 File Format:  Gerber RS274X*
G04 File Origin:  Cadence Allegro 16.5-S056*
G04 Origin Date:  Fri Jun 09 15:33:22 2017*
G04 *
G04 Layer:  BOARD GEOMETRY/SE_REF_L12_TBL*
G04 Layer:  BOARD GEOMETRY/SE_REF_L12_BOTTOM*
G04 Layer:  BOARD GEOMETRY/PANEL_OUTLINE*
G04 *
G04 Offset:    (0.00 0.00)*
G04 Mirror:    No*
G04 Mode:      Positive*
G04 Rotation:  0*
G04 FullContactRelief:  No*
G04 UndefLineWidth:     6.00*
G04 ================== end FILE IDENTIFICATION RECORD ====================*
%FSLAX35Y35*MOIN*%
%IR0*IPPOS*OFA0.00000B0.00000*MIA0B0*SFA1.00000B1.00000*%
%ADD10C,.02*%
%ADD11C,.006*%
%ADD12C,.00675*%
G75*
%LPD*%
G75*
G54D10*
G01X1985143Y1554618D02*
X2702643D01*
G01X1985143Y1623918D02*
Y1554618D01*
G01Y1589268D02*
X2702643D01*
G01X1985143Y1623918D02*
X2702643D01*
G01X2160143D02*
Y1554618D01*
G01X2387643Y1623918D02*
Y1554618D01*
G01X2492643Y1623918D02*
Y1554618D01*
G01X2702643Y1623918D02*
Y1554618D01*
G54D11*
G01X6250Y-185556D02*
Y-203056D01*
G01X1228Y-185556D02*
X11272D01*
G01X20038Y-203056D02*
Y-185556D01*
G01Y-194014D02*
X21130Y-192556D01*
X22222Y-191681D01*
X23968Y-191390D01*
X25278Y-191681D01*
X26807Y-192848D01*
X27462Y-194598D01*
Y-203056D01*
G01X41250Y-191390D02*
Y-203056D01*
G01Y-186723D02*
X40813Y-186431D01*
Y-185848D01*
X41250Y-185556D01*
X41687Y-185848D01*
Y-186431D01*
X41250Y-186723D01*
G01X55475Y-201015D02*
X56567Y-202181D01*
X58095Y-203056D01*
X59405D01*
X60715Y-202473D01*
X61588Y-201598D01*
X62025Y-200432D01*
X61807Y-198681D01*
X60933Y-197806D01*
X57003Y-196056D01*
X56130Y-194014D01*
X56567Y-192556D01*
X57440Y-191681D01*
X58750Y-191390D01*
X60060Y-191681D01*
X61370Y-192556D01*
G01X90693Y-207431D02*
X92222Y-208598D01*
X93968Y-208889D01*
X95496Y-208598D01*
X96807Y-207140D01*
X97680Y-205098D01*
Y-191390D01*
G01Y-193723D02*
X96807Y-192556D01*
X95496Y-191681D01*
X93968Y-191390D01*
X92222Y-191973D01*
X91130Y-193139D01*
X90256Y-195181D01*
X89820Y-197223D01*
X90038Y-198973D01*
X90912Y-201015D01*
X92222Y-202473D01*
X93968Y-203056D01*
X95278Y-202764D01*
X96807Y-201598D01*
X97680Y-200432D01*
G01X107975Y-195181D02*
X114962D01*
X114307Y-193139D01*
X113215Y-191973D01*
X111687Y-191390D01*
X110158Y-191681D01*
X108848Y-192556D01*
X107975Y-194598D01*
X107538Y-196348D01*
Y-198098D01*
X107975Y-199848D01*
X109067Y-201598D01*
X110377Y-202764D01*
X111905Y-203056D01*
X113433Y-202473D01*
X114962Y-200723D01*
G01X125693Y-203056D02*
Y-191390D01*
G01Y-193723D02*
X126785Y-192556D01*
X127877Y-191681D01*
X129405Y-191390D01*
X130496Y-191681D01*
X131807Y-192556D01*
G01X142320Y-203056D02*
Y-185556D01*
G01Y-194306D02*
X143412Y-192556D01*
X144722Y-191681D01*
X146032Y-191390D01*
X147996Y-191973D01*
X149307Y-193139D01*
X150180Y-195181D01*
Y-197514D01*
X149743Y-199848D01*
X148870Y-201598D01*
X147342Y-202764D01*
X146032Y-203056D01*
X144722Y-202764D01*
X143412Y-201890D01*
X142320Y-200432D01*
G01X160475Y-195181D02*
X167462D01*
X166807Y-193139D01*
X165715Y-191973D01*
X164187Y-191390D01*
X162658Y-191681D01*
X161348Y-192556D01*
X160475Y-194598D01*
X160038Y-196348D01*
Y-198098D01*
X160475Y-199848D01*
X161567Y-201598D01*
X162877Y-202764D01*
X164405Y-203056D01*
X165933Y-202473D01*
X167462Y-200723D01*
G01X178193Y-203056D02*
Y-191390D01*
G01Y-193723D02*
X179285Y-192556D01*
X180377Y-191681D01*
X181905Y-191390D01*
X182996Y-191681D01*
X184307Y-192556D01*
G01X216250Y-191390D02*
Y-203056D01*
G01Y-186723D02*
X215813Y-186431D01*
Y-185848D01*
X216250Y-185556D01*
X216687Y-185848D01*
Y-186431D01*
X216250Y-186723D01*
G01X230475Y-201015D02*
X231567Y-202181D01*
X233095Y-203056D01*
X234405D01*
X235715Y-202473D01*
X236588Y-201598D01*
X237025Y-200432D01*
X236807Y-198681D01*
X235933Y-197806D01*
X232003Y-196056D01*
X231130Y-194014D01*
X231567Y-192556D01*
X232440Y-191681D01*
X233750Y-191390D01*
X235060Y-191681D01*
X236370Y-192556D01*
G01X265256Y-207431D02*
X266785Y-208598D01*
X268095Y-208889D01*
X269842Y-208306D01*
X271152Y-206848D01*
X271807Y-204222D01*
Y-191390D01*
G01Y-186723D02*
X271370Y-186431D01*
Y-185848D01*
X271807Y-185556D01*
X272243Y-185848D01*
Y-186431D01*
X271807Y-186723D01*
G01X282538Y-191390D02*
Y-199556D01*
X283412Y-201598D01*
X284722Y-202764D01*
X286250Y-203056D01*
X287778Y-202764D01*
X289088Y-201598D01*
X289962Y-199556D01*
G01Y-203056D02*
Y-191390D01*
G01X300475Y-201015D02*
X301567Y-202181D01*
X303095Y-203056D01*
X304405D01*
X305715Y-202473D01*
X306588Y-201598D01*
X307025Y-200432D01*
X306807Y-198681D01*
X305933Y-197806D01*
X302003Y-196056D01*
X301130Y-194014D01*
X301567Y-192556D01*
X302440Y-191681D01*
X303750Y-191390D01*
X305060Y-191681D01*
X306370Y-192556D01*
G01X321250Y-185556D02*
Y-203056D01*
G01X318193Y-191390D02*
X324307D01*
G01X354940Y-203056D02*
Y-188181D01*
X355377Y-186723D01*
X356250Y-185848D01*
X357560Y-185556D01*
X358870Y-186139D01*
X359525Y-187598D01*
G01X356905Y-192556D02*
X352538D01*
G01X373750Y-203056D02*
X372440Y-202764D01*
X371130Y-201598D01*
X370256Y-199556D01*
X369820Y-197223D01*
X370256Y-194889D01*
X371130Y-192848D01*
X372440Y-191681D01*
X373750Y-191390D01*
X375060Y-191681D01*
X376370Y-192848D01*
X377243Y-194889D01*
X377462Y-197223D01*
X377243Y-199556D01*
X376370Y-201598D01*
X375060Y-202764D01*
X373750Y-203056D01*
G01X388193D02*
Y-191390D01*
G01Y-193723D02*
X389285Y-192556D01*
X390377Y-191681D01*
X391905Y-191390D01*
X392996Y-191681D01*
X394307Y-192556D01*
G01X421665Y-208306D02*
X422975Y-208889D01*
X424722Y-208306D01*
X425813Y-207140D01*
X426687Y-205681D01*
X427996Y-201015D01*
X430835Y-191390D01*
G01X423848D02*
X427996Y-201015D01*
G01X443750Y-203056D02*
X442440Y-202764D01*
X441130Y-201598D01*
X440256Y-199556D01*
X439820Y-197223D01*
X440256Y-194889D01*
X441130Y-192848D01*
X442440Y-191681D01*
X443750Y-191390D01*
X445060Y-191681D01*
X446370Y-192848D01*
X447243Y-194889D01*
X447462Y-197223D01*
X447243Y-199556D01*
X446370Y-201598D01*
X445060Y-202764D01*
X443750Y-203056D01*
G01X457538Y-191390D02*
Y-199556D01*
X458412Y-201598D01*
X459722Y-202764D01*
X461250Y-203056D01*
X462778Y-202764D01*
X464088Y-201598D01*
X464962Y-199556D01*
G01Y-203056D02*
Y-191390D01*
G01X475693Y-203056D02*
Y-191390D01*
G01Y-193723D02*
X476785Y-192556D01*
X477877Y-191681D01*
X479405Y-191390D01*
X480496Y-191681D01*
X481807Y-192556D01*
G01X510693Y-203056D02*
Y-191390D01*
G01Y-193723D02*
X511785Y-192556D01*
X512877Y-191681D01*
X514405Y-191390D01*
X515496Y-191681D01*
X516807Y-192556D01*
G01X527975Y-195181D02*
X534962D01*
X534307Y-193139D01*
X533215Y-191973D01*
X531687Y-191390D01*
X530158Y-191681D01*
X528848Y-192556D01*
X527975Y-194598D01*
X527538Y-196348D01*
Y-198098D01*
X527975Y-199848D01*
X529067Y-201598D01*
X530377Y-202764D01*
X531905Y-203056D01*
X533433Y-202473D01*
X534962Y-200723D01*
G01X547440Y-203056D02*
Y-188181D01*
X547877Y-186723D01*
X548750Y-185848D01*
X550060Y-185556D01*
X551370Y-186139D01*
X552025Y-187598D01*
G01X549405Y-192556D02*
X545038D01*
G01X562975Y-195181D02*
X569962D01*
X569307Y-193139D01*
X568215Y-191973D01*
X566687Y-191390D01*
X565158Y-191681D01*
X563848Y-192556D01*
X562975Y-194598D01*
X562538Y-196348D01*
Y-198098D01*
X562975Y-199848D01*
X564067Y-201598D01*
X565377Y-202764D01*
X566905Y-203056D01*
X568433Y-202473D01*
X569962Y-200723D01*
G01X580693Y-203056D02*
Y-191390D01*
G01Y-193723D02*
X581785Y-192556D01*
X582877Y-191681D01*
X584405Y-191390D01*
X585496Y-191681D01*
X586807Y-192556D01*
G01X597975Y-195181D02*
X604962D01*
X604307Y-193139D01*
X603215Y-191973D01*
X601687Y-191390D01*
X600158Y-191681D01*
X598848Y-192556D01*
X597975Y-194598D01*
X597538Y-196348D01*
Y-198098D01*
X597975Y-199848D01*
X599067Y-201598D01*
X600377Y-202764D01*
X601905Y-203056D01*
X603433Y-202473D01*
X604962Y-200723D01*
G01X615038Y-203056D02*
Y-191390D01*
G01Y-194306D02*
X615912Y-192848D01*
X617222Y-191681D01*
X618968Y-191390D01*
X620496Y-191681D01*
X621807Y-192848D01*
X622462Y-194889D01*
Y-203056D01*
G01X639743Y-192848D02*
X638215Y-191681D01*
X636905Y-191390D01*
X635158Y-191973D01*
X633848Y-193139D01*
X632975Y-195181D01*
X632756Y-197223D01*
X632975Y-199265D01*
X633848Y-201015D01*
X635158Y-202473D01*
X636905Y-203056D01*
X638433Y-202473D01*
X639743Y-201306D01*
G01X650475Y-195181D02*
X657462D01*
X656807Y-193139D01*
X655715Y-191973D01*
X654187Y-191390D01*
X652658Y-191681D01*
X651348Y-192556D01*
X650475Y-194598D01*
X650038Y-196348D01*
Y-198098D01*
X650475Y-199848D01*
X651567Y-201598D01*
X652877Y-202764D01*
X654405Y-203056D01*
X655933Y-202473D01*
X657462Y-200723D01*
G01X688750Y-185556D02*
Y-203056D01*
G01X685693Y-191390D02*
X691807D01*
G01X706250Y-203056D02*
X704940Y-202764D01*
X703630Y-201598D01*
X702756Y-199556D01*
X702320Y-197223D01*
X702756Y-194889D01*
X703630Y-192848D01*
X704940Y-191681D01*
X706250Y-191390D01*
X707560Y-191681D01*
X708870Y-192848D01*
X709743Y-194889D01*
X709962Y-197223D01*
X709743Y-199556D01*
X708870Y-201598D01*
X707560Y-202764D01*
X706250Y-203056D01*
G01X739940D02*
Y-188181D01*
X740377Y-186723D01*
X741250Y-185848D01*
X742560Y-185556D01*
X743870Y-186139D01*
X744525Y-187598D01*
G01X741905Y-192556D02*
X737538D01*
G01X758750Y-191390D02*
Y-203056D01*
G01Y-186723D02*
X758313Y-186431D01*
Y-185848D01*
X758750Y-185556D01*
X759187Y-185848D01*
Y-186431D01*
X758750Y-186723D01*
G01X772538Y-203056D02*
Y-191390D01*
G01Y-194306D02*
X773412Y-192848D01*
X774722Y-191681D01*
X776468Y-191390D01*
X777996Y-191681D01*
X779307Y-192848D01*
X779962Y-194889D01*
Y-203056D01*
G01X797680Y-185556D02*
Y-203056D01*
G01Y-200432D02*
X796807Y-201890D01*
X795496Y-202764D01*
X793968Y-203056D01*
X792222Y-202473D01*
X790912Y-201015D01*
X790038Y-199265D01*
X789820Y-197223D01*
X790038Y-195181D01*
X790912Y-193431D01*
X792222Y-191973D01*
X793968Y-191390D01*
X795496Y-191681D01*
X796588Y-192265D01*
X797680Y-193431D01*
G01X828750Y-185556D02*
Y-203056D01*
G01X825693Y-191390D02*
X831807D01*
G01X842538Y-203056D02*
Y-185556D01*
G01Y-194014D02*
X843630Y-192556D01*
X844722Y-191681D01*
X846468Y-191390D01*
X847778Y-191681D01*
X849307Y-192848D01*
X849962Y-194598D01*
Y-203056D01*
G01X860475Y-195181D02*
X867462D01*
X866807Y-193139D01*
X865715Y-191973D01*
X864187Y-191390D01*
X862658Y-191681D01*
X861348Y-192556D01*
X860475Y-194598D01*
X860038Y-196348D01*
Y-198098D01*
X860475Y-199848D01*
X861567Y-201598D01*
X862877Y-202764D01*
X864405Y-203056D01*
X865933Y-202473D01*
X867462Y-200723D01*
G01X894165D02*
X895912Y-202181D01*
X897877Y-203056D01*
X899623D01*
X901370Y-202181D01*
X902680Y-200723D01*
X903335Y-198681D01*
X902898Y-196640D01*
X901807Y-194889D01*
X899842Y-193723D01*
X897222Y-193139D01*
X895693Y-191973D01*
X895038Y-189931D01*
X895475Y-187889D01*
X896567Y-186431D01*
X898095Y-185556D01*
X899623D01*
X901152Y-186139D01*
X902462Y-187598D01*
G01X920617Y-203056D02*
X911883D01*
Y-185556D01*
X920617D01*
G01X917123Y-194014D02*
X911883D01*
G01X951250Y-191390D02*
Y-203056D01*
G01Y-186723D02*
X950813Y-186431D01*
Y-185848D01*
X951250Y-185556D01*
X951687Y-185848D01*
Y-186431D01*
X951250Y-186723D01*
G01X962200Y-203056D02*
Y-191390D01*
G01Y-194598D02*
X962855Y-193139D01*
X963947Y-191973D01*
X965475Y-191390D01*
X967003Y-191973D01*
X968095Y-193139D01*
X968750Y-194598D01*
Y-203056D01*
G01Y-194598D02*
X969405Y-193139D01*
X970496Y-191973D01*
X972025Y-191390D01*
X973553Y-191973D01*
X974645Y-193139D01*
X975300Y-194889D01*
Y-203056D01*
G01X982320Y-208889D02*
Y-191390D01*
G01Y-194014D02*
X983412Y-192556D01*
X984503Y-191681D01*
X986250Y-191390D01*
X987778Y-191681D01*
X989307Y-193139D01*
X989962Y-195181D01*
X990180Y-197223D01*
X989962Y-199265D01*
X989307Y-201306D01*
X987996Y-202473D01*
X986250Y-203056D01*
X984722Y-202764D01*
X983193Y-201890D01*
X982320Y-200723D01*
G01X1000475Y-195181D02*
X1007462D01*
X1006807Y-193139D01*
X1005715Y-191973D01*
X1004187Y-191390D01*
X1002658Y-191681D01*
X1001348Y-192556D01*
X1000475Y-194598D01*
X1000038Y-196348D01*
Y-198098D01*
X1000475Y-199848D01*
X1001567Y-201598D01*
X1002877Y-202764D01*
X1004405Y-203056D01*
X1005933Y-202473D01*
X1007462Y-200723D01*
G01X1025180Y-185556D02*
Y-203056D01*
G01Y-200432D02*
X1024307Y-201890D01*
X1022996Y-202764D01*
X1021468Y-203056D01*
X1019722Y-202473D01*
X1018412Y-201015D01*
X1017538Y-199265D01*
X1017320Y-197223D01*
X1017538Y-195181D01*
X1018412Y-193431D01*
X1019722Y-191973D01*
X1021468Y-191390D01*
X1022996Y-191681D01*
X1024088Y-192265D01*
X1025180Y-193431D01*
G01X1042680Y-203056D02*
Y-191390D01*
G01Y-193431D02*
X1041807Y-192265D01*
X1040496Y-191681D01*
X1038968Y-191390D01*
X1037440Y-191973D01*
X1036130Y-193139D01*
X1035256Y-194889D01*
X1034820Y-197223D01*
X1035256Y-199556D01*
X1036130Y-201306D01*
X1037440Y-202473D01*
X1038968Y-203056D01*
X1040496Y-202764D01*
X1041807Y-201890D01*
X1042680Y-200723D01*
G01X1052538Y-203056D02*
Y-191390D01*
G01Y-194306D02*
X1053412Y-192848D01*
X1054722Y-191681D01*
X1056468Y-191390D01*
X1057996Y-191681D01*
X1059307Y-192848D01*
X1059962Y-194889D01*
Y-203056D01*
G01X1077243Y-192848D02*
X1075715Y-191681D01*
X1074405Y-191390D01*
X1072658Y-191973D01*
X1071348Y-193139D01*
X1070475Y-195181D01*
X1070256Y-197223D01*
X1070475Y-199265D01*
X1071348Y-201015D01*
X1072658Y-202473D01*
X1074405Y-203056D01*
X1075933Y-202473D01*
X1077243Y-201306D01*
G01X1087975Y-195181D02*
X1094962D01*
X1094307Y-193139D01*
X1093215Y-191973D01*
X1091687Y-191390D01*
X1090158Y-191681D01*
X1088848Y-192556D01*
X1087975Y-194598D01*
X1087538Y-196348D01*
Y-198098D01*
X1087975Y-199848D01*
X1089067Y-201598D01*
X1090377Y-202764D01*
X1091905Y-203056D01*
X1093433Y-202473D01*
X1094962Y-200723D01*
G01X1126250Y-185556D02*
Y-203056D01*
G01X1123193Y-191390D02*
X1129307D01*
G01X1140693Y-203056D02*
Y-191390D01*
G01Y-193723D02*
X1141785Y-192556D01*
X1142877Y-191681D01*
X1144405Y-191390D01*
X1145496Y-191681D01*
X1146807Y-192556D01*
G01X1165180Y-203056D02*
Y-191390D01*
G01Y-193431D02*
X1164307Y-192265D01*
X1162996Y-191681D01*
X1161468Y-191390D01*
X1159940Y-191973D01*
X1158630Y-193139D01*
X1157756Y-194889D01*
X1157320Y-197223D01*
X1157756Y-199556D01*
X1158630Y-201306D01*
X1159940Y-202473D01*
X1161468Y-203056D01*
X1162996Y-202764D01*
X1164307Y-201890D01*
X1165180Y-200723D01*
G01X1182243Y-192848D02*
X1180715Y-191681D01*
X1179405Y-191390D01*
X1177658Y-191973D01*
X1176348Y-193139D01*
X1175475Y-195181D01*
X1175256Y-197223D01*
X1175475Y-199265D01*
X1176348Y-201015D01*
X1177658Y-202473D01*
X1179405Y-203056D01*
X1180933Y-202473D01*
X1182243Y-201306D01*
G01X1192975Y-195181D02*
X1199962D01*
X1199307Y-193139D01*
X1198215Y-191973D01*
X1196687Y-191390D01*
X1195158Y-191681D01*
X1193848Y-192556D01*
X1192975Y-194598D01*
X1192538Y-196348D01*
Y-198098D01*
X1192975Y-199848D01*
X1194067Y-201598D01*
X1195377Y-202764D01*
X1196905Y-203056D01*
X1198433Y-202473D01*
X1199962Y-200723D01*
G01X1210475Y-201015D02*
X1211567Y-202181D01*
X1213095Y-203056D01*
X1214405D01*
X1215715Y-202473D01*
X1216588Y-201598D01*
X1217025Y-200432D01*
X1216807Y-198681D01*
X1215933Y-197806D01*
X1212003Y-196056D01*
X1211130Y-194014D01*
X1211567Y-192556D01*
X1212440Y-191681D01*
X1213750Y-191390D01*
X1215060Y-191681D01*
X1216370Y-192556D01*
G01X1248750Y-191390D02*
Y-203056D01*
G01Y-186723D02*
X1248313Y-186431D01*
Y-185848D01*
X1248750Y-185556D01*
X1249187Y-185848D01*
Y-186431D01*
X1248750Y-186723D01*
G01X1262538Y-203056D02*
Y-191390D01*
G01Y-194306D02*
X1263412Y-192848D01*
X1264722Y-191681D01*
X1266468Y-191390D01*
X1267996Y-191681D01*
X1269307Y-192848D01*
X1269962Y-194889D01*
Y-203056D01*
G01X1301250D02*
Y-185556D01*
G01X1322680Y-203056D02*
Y-191390D01*
G01Y-193431D02*
X1321807Y-192265D01*
X1320496Y-191681D01*
X1318968Y-191390D01*
X1317440Y-191973D01*
X1316130Y-193139D01*
X1315256Y-194889D01*
X1314820Y-197223D01*
X1315256Y-199556D01*
X1316130Y-201306D01*
X1317440Y-202473D01*
X1318968Y-203056D01*
X1320496Y-202764D01*
X1321807Y-201890D01*
X1322680Y-200723D01*
G01X1331665Y-208306D02*
X1332975Y-208889D01*
X1334722Y-208306D01*
X1335813Y-207140D01*
X1336687Y-205681D01*
X1337996Y-201015D01*
X1340835Y-191390D01*
G01X1333848D02*
X1337996Y-201015D01*
G01X1350475Y-195181D02*
X1357462D01*
X1356807Y-193139D01*
X1355715Y-191973D01*
X1354187Y-191390D01*
X1352658Y-191681D01*
X1351348Y-192556D01*
X1350475Y-194598D01*
X1350038Y-196348D01*
Y-198098D01*
X1350475Y-199848D01*
X1351567Y-201598D01*
X1352877Y-202764D01*
X1354405Y-203056D01*
X1355933Y-202473D01*
X1357462Y-200723D01*
G01X1368193Y-203056D02*
Y-191390D01*
G01Y-193723D02*
X1369285Y-192556D01*
X1370377Y-191681D01*
X1371905Y-191390D01*
X1372996Y-191681D01*
X1374307Y-192556D01*
G01X1401883Y-185556D02*
Y-203056D01*
X1410617D01*
G01X1423750D02*
Y-185556D01*
X1421130Y-189056D01*
G01Y-203056D02*
X1426370D01*
G01X1437102Y-188473D02*
X1438412Y-186723D01*
X1439940Y-185848D01*
X1441687Y-185556D01*
X1443870Y-186139D01*
X1445398Y-187598D01*
X1445835Y-189347D01*
X1445617Y-191098D01*
X1444743Y-192556D01*
X1440377Y-195473D01*
X1438412Y-197514D01*
X1437102Y-200432D01*
X1436665Y-203056D01*
X1445835D01*
G01X1458750Y-203639D02*
X1458313Y-203348D01*
Y-202764D01*
X1458750Y-202473D01*
X1459187Y-202764D01*
Y-203348D01*
X1458750Y-203639D01*
G01X2008773Y1616518D02*
X2014013D01*
G01X2011393D02*
Y1599018D01*
G01X2008773D02*
X2014013D01*
G01X2023216D02*
Y1616518D01*
X2028893Y1601935D01*
X2034570Y1616518D01*
Y1599018D01*
G01X2042026D02*
Y1616518D01*
X2047266D01*
X2049013Y1615643D01*
X2050323Y1613601D01*
X2050760Y1611268D01*
X2050323Y1608935D01*
X2049231Y1607185D01*
X2047266Y1606309D01*
X2042026D01*
G01X2062801Y1593185D02*
X2060618Y1596101D01*
X2059526Y1599018D01*
Y1610684D01*
X2060618Y1613601D01*
X2062801Y1616518D01*
G01X2081393Y1599018D02*
X2079646Y1599310D01*
X2078118Y1600476D01*
X2076808Y1602226D01*
X2075934Y1604268D01*
X2075498Y1606601D01*
Y1608935D01*
X2075934Y1611268D01*
X2076808Y1613310D01*
X2078118Y1615059D01*
X2079646Y1616226D01*
X2081393Y1616518D01*
X2083139Y1616226D01*
X2084668Y1615059D01*
X2085978Y1613310D01*
X2086852Y1611268D01*
X2087288Y1608935D01*
Y1606601D01*
X2086852Y1604268D01*
X2085978Y1602226D01*
X2084668Y1600476D01*
X2083139Y1599310D01*
X2081393Y1599018D01*
G01X2095181D02*
Y1616518D01*
G01Y1608060D02*
X2096273Y1609518D01*
X2097365Y1610393D01*
X2099111Y1610684D01*
X2100421Y1610393D01*
X2101950Y1609226D01*
X2102605Y1607476D01*
Y1599018D01*
G01X2109843D02*
Y1610684D01*
G01Y1607476D02*
X2110498Y1608935D01*
X2111590Y1610101D01*
X2113118Y1610684D01*
X2114646Y1610101D01*
X2115738Y1608935D01*
X2116393Y1607476D01*
Y1599018D01*
G01Y1607476D02*
X2117048Y1608935D01*
X2118139Y1610101D01*
X2119668Y1610684D01*
X2121196Y1610101D01*
X2122288Y1608935D01*
X2122943Y1607185D01*
Y1599018D01*
G01X2134985Y1593185D02*
X2137168Y1596101D01*
X2138260Y1599018D01*
Y1610684D01*
X2137168Y1613601D01*
X2134985Y1616518D01*
G01X1987108Y1636001D02*
X1988855Y1634543D01*
X1990820Y1633668D01*
X1992566D01*
X1994313Y1634543D01*
X1995623Y1636001D01*
X1996278Y1638043D01*
X1995841Y1640084D01*
X1994750Y1641835D01*
X1992785Y1643001D01*
X1990165Y1643585D01*
X1988636Y1644751D01*
X1987981Y1646793D01*
X1988418Y1648835D01*
X1989510Y1650293D01*
X1991038Y1651168D01*
X1992566D01*
X1994095Y1650585D01*
X1995405Y1649126D01*
G01X2013560Y1633668D02*
X2004826D01*
Y1651168D01*
X2013560D01*
G01X2010066Y1642710D02*
X2004826D01*
G01X2041573Y1651168D02*
X2046813D01*
G01X2044193D02*
Y1633668D01*
G01X2041573D02*
X2046813D01*
G01X2056016D02*
Y1651168D01*
X2061693Y1636585D01*
X2067370Y1651168D01*
Y1633668D01*
G01X2074826D02*
Y1651168D01*
X2080066D01*
X2081813Y1650293D01*
X2083123Y1648251D01*
X2083560Y1645918D01*
X2083123Y1643585D01*
X2082031Y1641835D01*
X2080066Y1640959D01*
X2074826D01*
G01X2101060Y1633668D02*
X2092326D01*
Y1651168D01*
X2101060D01*
G01X2097566Y1642710D02*
X2092326D01*
G01X2109390Y1633668D02*
Y1651168D01*
X2113756D01*
X2115503Y1650293D01*
X2116813Y1649126D01*
X2117905Y1647377D01*
X2118778Y1645334D01*
X2118996Y1642418D01*
X2118778Y1639501D01*
X2117905Y1637459D01*
X2116813Y1635709D01*
X2115503Y1634543D01*
X2113756Y1633668D01*
X2109390D01*
G01X2126234D02*
X2131693Y1651168D01*
X2137152Y1633668D01*
G01X2135186Y1639793D02*
X2128199D01*
G01X2144171Y1633668D02*
Y1651168D01*
X2154215Y1633668D01*
Y1651168D01*
G01X2171496Y1649709D02*
X2170186Y1650585D01*
X2168658Y1651168D01*
X2166911D01*
X2164946Y1650293D01*
X2163418Y1648835D01*
X2162326Y1647084D01*
X2161453Y1644168D01*
X2161234Y1641543D01*
X2161671Y1638918D01*
X2162326Y1637168D01*
X2163636Y1635418D01*
X2165165Y1634251D01*
X2166693Y1633668D01*
X2168221D01*
X2169750Y1634251D01*
X2171060Y1635126D01*
X2172152Y1636292D01*
G01X2188560Y1633668D02*
X2179826D01*
Y1651168D01*
X2188560D01*
G01X2185066Y1642710D02*
X2179826D01*
G01X2219193Y1651168D02*
Y1633668D01*
G01X2214171Y1651168D02*
X2224215D01*
G01X2231234Y1633668D02*
X2236693Y1651168D01*
X2242152Y1633668D01*
G01X2240186Y1639793D02*
X2233199D01*
G01X2255939Y1643001D02*
X2256813Y1643876D01*
X2257468Y1645334D01*
X2257905Y1647377D01*
X2257468Y1649126D01*
X2256595Y1650293D01*
X2255066Y1651168D01*
X2249171D01*
Y1633668D01*
X2256376D01*
X2257905Y1634834D01*
X2258778Y1636585D01*
X2259215Y1638626D01*
X2258778Y1640668D01*
X2257468Y1642418D01*
X2255939Y1643001D01*
X2249171D01*
G01X2267326Y1651168D02*
Y1633668D01*
X2276060D01*
G01X2293560D02*
X2284826D01*
Y1651168D01*
X2293560D01*
G01X2290066Y1642710D02*
X2284826D01*
G01X2306693Y1633085D02*
X2306256Y1633376D01*
Y1633960D01*
X2306693Y1634251D01*
X2307130Y1633960D01*
Y1633376D01*
X2306693Y1633085D01*
G01Y1640959D02*
X2306256Y1641251D01*
Y1641835D01*
X2306693Y1642126D01*
X2307130Y1641835D01*
Y1641251D01*
X2306693Y1640959D01*
G01X2337326Y1651168D02*
Y1633668D01*
X2346060D01*
G01X2359193D02*
Y1651168D01*
X2356573Y1647668D01*
G01Y1633668D02*
X2361813D01*
G01X2372545Y1648251D02*
X2373855Y1650001D01*
X2375383Y1650876D01*
X2377130Y1651168D01*
X2379313Y1650585D01*
X2380841Y1649126D01*
X2381278Y1647377D01*
X2381060Y1645626D01*
X2380186Y1644168D01*
X2375820Y1641251D01*
X2373855Y1639210D01*
X2372545Y1636292D01*
X2372108Y1633668D01*
X2381278D01*
G01X2041590Y1566992D02*
X2042899Y1565534D01*
X2044428Y1564660D01*
X2046393Y1564368D01*
X2048358Y1564951D01*
X2049886Y1566118D01*
X2050978Y1568159D01*
X2051196Y1570493D01*
X2050760Y1572826D01*
X2049668Y1574285D01*
X2048139Y1575451D01*
X2046611Y1575743D01*
X2045083Y1575451D01*
X2043118Y1574285D01*
X2043773Y1581868D01*
X2049668D01*
G01X2063893D02*
X2062146Y1581285D01*
X2060836Y1579826D01*
X2059963Y1578077D01*
X2059308Y1575743D01*
X2059090Y1573118D01*
X2059308Y1570493D01*
X2059963Y1568159D01*
X2060836Y1566409D01*
X2062146Y1564951D01*
X2063893Y1564368D01*
X2065639Y1564951D01*
X2066950Y1566409D01*
X2067823Y1568159D01*
X2068478Y1570493D01*
X2068696Y1573118D01*
X2068478Y1575743D01*
X2067823Y1578077D01*
X2066950Y1579826D01*
X2065639Y1581285D01*
X2063893Y1581868D01*
G01X2081393Y1563785D02*
X2080956Y1564076D01*
Y1564660D01*
X2081393Y1564951D01*
X2081830Y1564660D01*
Y1564076D01*
X2081393Y1563785D01*
G01X2098893Y1581868D02*
X2097146Y1581285D01*
X2095836Y1579826D01*
X2094963Y1578077D01*
X2094308Y1575743D01*
X2094090Y1573118D01*
X2094308Y1570493D01*
X2094963Y1568159D01*
X2095836Y1566409D01*
X2097146Y1564951D01*
X2098893Y1564368D01*
X2100639Y1564951D01*
X2101950Y1566409D01*
X2102823Y1568159D01*
X2103478Y1570493D01*
X2103696Y1573118D01*
X2103478Y1575743D01*
X2102823Y1578077D01*
X2101950Y1579826D01*
X2100639Y1581285D01*
X2098893Y1581868D01*
G01X2179843Y1616518D02*
X2182899Y1599018D01*
X2186393Y1616518D01*
X2189886Y1599018D01*
X2192943Y1616518D01*
G01X2201273D02*
X2206513D01*
G01X2203893D02*
Y1599018D01*
G01X2201273D02*
X2206513D01*
G01X2216590D02*
Y1616518D01*
X2220956D01*
X2222703Y1615643D01*
X2224013Y1614476D01*
X2225105Y1612727D01*
X2225978Y1610684D01*
X2226196Y1607768D01*
X2225978Y1604851D01*
X2225105Y1602809D01*
X2224013Y1601059D01*
X2222703Y1599893D01*
X2220956Y1599018D01*
X2216590D01*
G01X2238893Y1616518D02*
Y1599018D01*
G01X2233871Y1616518D02*
X2243915D01*
G01X2251808Y1599018D02*
Y1616518D01*
G01X2260978D02*
Y1599018D01*
G01Y1607768D02*
X2251808D01*
G01X2272801Y1593185D02*
X2270618Y1596101D01*
X2269526Y1599018D01*
Y1610684D01*
X2270618Y1613601D01*
X2272801Y1616518D01*
G01X2284843Y1599018D02*
Y1610684D01*
G01Y1607476D02*
X2285498Y1608935D01*
X2286590Y1610101D01*
X2288118Y1610684D01*
X2289646Y1610101D01*
X2290738Y1608935D01*
X2291393Y1607476D01*
Y1599018D01*
G01Y1607476D02*
X2292048Y1608935D01*
X2293139Y1610101D01*
X2294668Y1610684D01*
X2296196Y1610101D01*
X2297288Y1608935D01*
X2297943Y1607185D01*
Y1599018D01*
G01X2308893Y1610684D02*
Y1599018D01*
G01Y1615351D02*
X2308456Y1615643D01*
Y1616226D01*
X2308893Y1616518D01*
X2309330Y1616226D01*
Y1615643D01*
X2308893Y1615351D01*
G01X2326393Y1599018D02*
Y1616518D01*
G01X2340618Y1601059D02*
X2341710Y1599893D01*
X2343238Y1599018D01*
X2344548D01*
X2345858Y1599601D01*
X2346731Y1600476D01*
X2347168Y1601642D01*
X2346950Y1603393D01*
X2346076Y1604268D01*
X2342146Y1606018D01*
X2341273Y1608060D01*
X2341710Y1609518D01*
X2342583Y1610393D01*
X2343893Y1610684D01*
X2345203Y1610393D01*
X2346513Y1609518D01*
G01X2362485Y1593185D02*
X2364668Y1596101D01*
X2365760Y1599018D01*
Y1610684D01*
X2364668Y1613601D01*
X2362485Y1616518D01*
G01X2243495Y1571659D02*
X2245023Y1573701D01*
X2246333Y1574868D01*
X2248080Y1575451D01*
X2249608Y1574868D01*
X2250700Y1573701D01*
X2251573Y1571951D01*
X2251791Y1569910D01*
X2251573Y1568159D01*
X2250700Y1566409D01*
X2249389Y1564951D01*
X2247861Y1564368D01*
X2246115Y1564951D01*
X2244586Y1566701D01*
X2243713Y1569326D01*
X2243495Y1572243D01*
X2243931Y1576034D01*
X2244586Y1578077D01*
X2245678Y1580118D01*
X2247206Y1581576D01*
X2248735Y1581868D01*
X2250263Y1581285D01*
X2251355Y1579826D01*
G01X2265143Y1563785D02*
X2264706Y1564076D01*
Y1564660D01*
X2265143Y1564951D01*
X2265580Y1564660D01*
Y1564076D01*
X2265143Y1563785D01*
G01X2282206Y1564368D02*
X2282643Y1568159D01*
X2283298Y1571368D01*
X2284171Y1574285D01*
X2285263Y1577493D01*
X2287010Y1581868D01*
X2278276D01*
G01X2295340Y1566992D02*
X2296649Y1565534D01*
X2298178Y1564660D01*
X2300143Y1564368D01*
X2302108Y1564951D01*
X2303636Y1566118D01*
X2304728Y1568159D01*
X2304946Y1570493D01*
X2304510Y1572826D01*
X2303418Y1574285D01*
X2301889Y1575451D01*
X2300361Y1575743D01*
X2298833Y1575451D01*
X2296868Y1574285D01*
X2297523Y1581868D01*
X2303418D01*
G01X2426808Y1566701D02*
X2428555Y1565243D01*
X2430520Y1564368D01*
X2432266D01*
X2434013Y1565243D01*
X2435323Y1566701D01*
X2435978Y1568743D01*
X2435541Y1570784D01*
X2434450Y1572535D01*
X2432485Y1573701D01*
X2429865Y1574285D01*
X2428336Y1575451D01*
X2427681Y1577493D01*
X2428118Y1579535D01*
X2429210Y1580993D01*
X2430738Y1581868D01*
X2432266D01*
X2433795Y1581285D01*
X2435105Y1579826D01*
G01X2453260Y1564368D02*
X2444526D01*
Y1581868D01*
X2453260D01*
G01X2449766Y1573410D02*
X2444526D01*
G01X2413893Y1616518D02*
Y1599018D01*
G01X2408871Y1616518D02*
X2418915D01*
G01X2431393Y1599018D02*
Y1606893D01*
X2427026Y1616518D01*
G01X2435760D02*
X2431393Y1606893D01*
G01X2444526Y1599018D02*
Y1616518D01*
X2449766D01*
X2451513Y1615643D01*
X2452823Y1613601D01*
X2453260Y1611268D01*
X2452823Y1608935D01*
X2451731Y1607185D01*
X2449766Y1606309D01*
X2444526D01*
G01X2470760Y1599018D02*
X2462026D01*
Y1616518D01*
X2470760D01*
G01X2467266Y1608060D02*
X2462026D01*
G01X2514526Y1599018D02*
Y1616518D01*
X2519985D01*
X2521731Y1615643D01*
X2522823Y1614476D01*
X2523260Y1612143D01*
X2522823Y1609809D01*
X2521513Y1608351D01*
X2519985Y1607476D01*
X2514526D01*
G01X2519985D02*
X2523260Y1599018D01*
G01X2533118Y1606893D02*
X2540105D01*
X2539450Y1608935D01*
X2538358Y1610101D01*
X2536830Y1610684D01*
X2535301Y1610393D01*
X2533991Y1609518D01*
X2533118Y1607476D01*
X2532681Y1605726D01*
Y1603976D01*
X2533118Y1602226D01*
X2534210Y1600476D01*
X2535520Y1599310D01*
X2537048Y1599018D01*
X2538576Y1599601D01*
X2540105Y1601351D01*
G01X2552583Y1599018D02*
Y1613893D01*
X2553020Y1615351D01*
X2553893Y1616226D01*
X2555203Y1616518D01*
X2556513Y1615935D01*
X2557168Y1614476D01*
G01X2554548Y1609518D02*
X2550181D01*
G01X2571393Y1598435D02*
X2570956Y1598726D01*
Y1599310D01*
X2571393Y1599601D01*
X2571830Y1599310D01*
Y1598726D01*
X2571393Y1598435D01*
G01X2602026Y1599018D02*
Y1616518D01*
X2607266D01*
X2609013Y1615643D01*
X2610323Y1613601D01*
X2610760Y1611268D01*
X2610323Y1608935D01*
X2609231Y1607185D01*
X2607266Y1606309D01*
X2602026D01*
G01X2623893Y1599018D02*
Y1616518D01*
G01X2645323Y1599018D02*
Y1610684D01*
G01Y1608643D02*
X2644450Y1609809D01*
X2643139Y1610393D01*
X2641611Y1610684D01*
X2640083Y1610101D01*
X2638773Y1608935D01*
X2637899Y1607185D01*
X2637463Y1604851D01*
X2637899Y1602518D01*
X2638773Y1600768D01*
X2640083Y1599601D01*
X2641611Y1599018D01*
X2643139Y1599310D01*
X2644450Y1600184D01*
X2645323Y1601351D01*
G01X2655181Y1599018D02*
Y1610684D01*
G01Y1607768D02*
X2656055Y1609226D01*
X2657365Y1610393D01*
X2659111Y1610684D01*
X2660639Y1610393D01*
X2661950Y1609226D01*
X2662605Y1607185D01*
Y1599018D01*
G01X2673118Y1606893D02*
X2680105D01*
X2679450Y1608935D01*
X2678358Y1610101D01*
X2676830Y1610684D01*
X2675301Y1610393D01*
X2673991Y1609518D01*
X2673118Y1607476D01*
X2672681Y1605726D01*
Y1603976D01*
X2673118Y1602226D01*
X2674210Y1600476D01*
X2675520Y1599310D01*
X2677048Y1599018D01*
X2678576Y1599601D01*
X2680105Y1601351D01*
G01X2575776Y1581868D02*
Y1564368D01*
X2584510D01*
G01X2597643D02*
Y1581868D01*
X2595023Y1578368D01*
G01Y1564368D02*
X2600263D01*
G01X2615143D02*
Y1581868D01*
X2612523Y1578368D01*
G01Y1564368D02*
X2617763D01*
G01X2794193Y1576034D02*
Y1564368D01*
G01Y1580701D02*
X2793756Y1580993D01*
Y1581576D01*
X2794193Y1581868D01*
X2794630Y1581576D01*
Y1580993D01*
X2794193Y1580701D01*
G01X2808418Y1566409D02*
X2809510Y1565243D01*
X2811038Y1564368D01*
X2812348D01*
X2813658Y1564951D01*
X2814531Y1565826D01*
X2814968Y1566992D01*
X2814750Y1568743D01*
X2813876Y1569618D01*
X2809946Y1571368D01*
X2809073Y1573410D01*
X2809510Y1574868D01*
X2810383Y1575743D01*
X2811693Y1576034D01*
X2813003Y1575743D01*
X2814313Y1574868D01*
G01X2841671Y1564368D02*
Y1581868D01*
X2851715Y1564368D01*
Y1581868D01*
G01X2864193Y1564368D02*
X2862446Y1564660D01*
X2860918Y1565826D01*
X2859608Y1567576D01*
X2858734Y1569618D01*
X2858298Y1571951D01*
Y1574285D01*
X2858734Y1576618D01*
X2859608Y1578660D01*
X2860918Y1580409D01*
X2862446Y1581576D01*
X2864193Y1581868D01*
X2865939Y1581576D01*
X2867468Y1580409D01*
X2868778Y1578660D01*
X2869652Y1576618D01*
X2870088Y1574285D01*
Y1571951D01*
X2869652Y1569618D01*
X2868778Y1567576D01*
X2867468Y1565826D01*
X2865939Y1564660D01*
X2864193Y1564368D01*
G01X2881693Y1581868D02*
Y1564368D01*
G01X2876671Y1581868D02*
X2886715D01*
G01X2912981Y1576034D02*
Y1567868D01*
X2913855Y1565826D01*
X2915165Y1564660D01*
X2916693Y1564368D01*
X2918221Y1564660D01*
X2919531Y1565826D01*
X2920405Y1567868D01*
G01Y1564368D02*
Y1576034D01*
G01X2930918Y1566409D02*
X2932010Y1565243D01*
X2933538Y1564368D01*
X2934848D01*
X2936158Y1564951D01*
X2937031Y1565826D01*
X2937468Y1566992D01*
X2937250Y1568743D01*
X2936376Y1569618D01*
X2932446Y1571368D01*
X2931573Y1573410D01*
X2932010Y1574868D01*
X2932883Y1575743D01*
X2934193Y1576034D01*
X2935503Y1575743D01*
X2936813Y1574868D01*
G01X2948418Y1572243D02*
X2955405D01*
X2954750Y1574285D01*
X2953658Y1575451D01*
X2952130Y1576034D01*
X2950601Y1575743D01*
X2949291Y1574868D01*
X2948418Y1572826D01*
X2947981Y1571076D01*
Y1569326D01*
X2948418Y1567576D01*
X2949510Y1565826D01*
X2950820Y1564660D01*
X2952348Y1564368D01*
X2953876Y1564951D01*
X2955405Y1566701D01*
G01X2973123Y1581868D02*
Y1564368D01*
G01Y1566992D02*
X2972250Y1565534D01*
X2970939Y1564660D01*
X2969411Y1564368D01*
X2967665Y1564951D01*
X2966355Y1566409D01*
X2965481Y1568159D01*
X2965263Y1570201D01*
X2965481Y1572243D01*
X2966355Y1573993D01*
X2967665Y1575451D01*
X2969411Y1576034D01*
X2970939Y1575743D01*
X2972031Y1575159D01*
X2973123Y1573993D01*
G01X2719390Y1598435D02*
X2728996Y1611268D01*
G01X2724193Y1613601D02*
Y1596101D01*
G01X2728996Y1598435D02*
X2719390Y1611268D01*
G01X2717643Y1604851D02*
X2730743D01*
G01X2756355D02*
X2762031D01*
G01X2789390Y1599018D02*
Y1616518D01*
X2793756D01*
X2795503Y1615643D01*
X2796813Y1614476D01*
X2797905Y1612727D01*
X2798778Y1610684D01*
X2798996Y1607768D01*
X2798778Y1604851D01*
X2797905Y1602809D01*
X2796813Y1601059D01*
X2795503Y1599893D01*
X2793756Y1599018D01*
X2789390D01*
G01X2808418Y1606893D02*
X2815405D01*
X2814750Y1608935D01*
X2813658Y1610101D01*
X2812130Y1610684D01*
X2810601Y1610393D01*
X2809291Y1609518D01*
X2808418Y1607476D01*
X2807981Y1605726D01*
Y1603976D01*
X2808418Y1602226D01*
X2809510Y1600476D01*
X2810820Y1599310D01*
X2812348Y1599018D01*
X2813876Y1599601D01*
X2815405Y1601351D01*
G01X2825481Y1599018D02*
Y1610684D01*
G01Y1607768D02*
X2826355Y1609226D01*
X2827665Y1610393D01*
X2829411Y1610684D01*
X2830939Y1610393D01*
X2832250Y1609226D01*
X2832905Y1607185D01*
Y1599018D01*
G01X2846693D02*
X2845383Y1599310D01*
X2844073Y1600476D01*
X2843199Y1602518D01*
X2842763Y1604851D01*
X2843199Y1607185D01*
X2844073Y1609226D01*
X2845383Y1610393D01*
X2846693Y1610684D01*
X2848003Y1610393D01*
X2849313Y1609226D01*
X2850186Y1607185D01*
X2850405Y1604851D01*
X2850186Y1602518D01*
X2849313Y1600476D01*
X2848003Y1599310D01*
X2846693Y1599018D01*
G01X2864193Y1616518D02*
Y1599018D01*
G01X2861136Y1610684D02*
X2867250D01*
G01X2878418Y1606893D02*
X2885405D01*
X2884750Y1608935D01*
X2883658Y1610101D01*
X2882130Y1610684D01*
X2880601Y1610393D01*
X2879291Y1609518D01*
X2878418Y1607476D01*
X2877981Y1605726D01*
Y1603976D01*
X2878418Y1602226D01*
X2879510Y1600476D01*
X2880820Y1599310D01*
X2882348Y1599018D01*
X2883876Y1599601D01*
X2885405Y1601351D01*
G01X2895918Y1601059D02*
X2897010Y1599893D01*
X2898538Y1599018D01*
X2899848D01*
X2901158Y1599601D01*
X2902031Y1600476D01*
X2902468Y1601642D01*
X2902250Y1603393D01*
X2901376Y1604268D01*
X2897446Y1606018D01*
X2896573Y1608060D01*
X2897010Y1609518D01*
X2897883Y1610393D01*
X2899193Y1610684D01*
X2900503Y1610393D01*
X2901813Y1609518D01*
G01X2934193Y1616518D02*
Y1599018D01*
G01X2931136Y1610684D02*
X2937250D01*
G01X2947981Y1599018D02*
Y1616518D01*
G01Y1608060D02*
X2949073Y1609518D01*
X2950165Y1610393D01*
X2951911Y1610684D01*
X2953221Y1610393D01*
X2954750Y1609226D01*
X2955405Y1607476D01*
Y1599018D01*
G01X2973123D02*
Y1610684D01*
G01Y1608643D02*
X2972250Y1609809D01*
X2970939Y1610393D01*
X2969411Y1610684D01*
X2967883Y1610101D01*
X2966573Y1608935D01*
X2965699Y1607185D01*
X2965263Y1604851D01*
X2965699Y1602518D01*
X2966573Y1600768D01*
X2967883Y1599601D01*
X2969411Y1599018D01*
X2970939Y1599310D01*
X2972250Y1600184D01*
X2973123Y1601351D01*
G01X2986693Y1616518D02*
Y1599018D01*
G01X2983636Y1610684D02*
X2989750D01*
G01X3021693Y1616518D02*
Y1599018D01*
G01X3018636Y1610684D02*
X3024750D01*
G01X3035481Y1599018D02*
Y1616518D01*
G01Y1608060D02*
X3036573Y1609518D01*
X3037665Y1610393D01*
X3039411Y1610684D01*
X3040721Y1610393D01*
X3042250Y1609226D01*
X3042905Y1607476D01*
Y1599018D01*
G01X3056693Y1610684D02*
Y1599018D01*
G01Y1615351D02*
X3056256Y1615643D01*
Y1616226D01*
X3056693Y1616518D01*
X3057130Y1616226D01*
Y1615643D01*
X3056693Y1615351D01*
G01X3070918Y1601059D02*
X3072010Y1599893D01*
X3073538Y1599018D01*
X3074848D01*
X3076158Y1599601D01*
X3077031Y1600476D01*
X3077468Y1601642D01*
X3077250Y1603393D01*
X3076376Y1604268D01*
X3072446Y1606018D01*
X3071573Y1608060D01*
X3072010Y1609518D01*
X3072883Y1610393D01*
X3074193Y1610684D01*
X3075503Y1610393D01*
X3076813Y1609518D01*
G01X3106573Y1616518D02*
X3111813D01*
G01X3109193D02*
Y1599018D01*
G01X3106573D02*
X3111813D01*
G01X3120143D02*
Y1610684D01*
G01Y1607476D02*
X3120798Y1608935D01*
X3121890Y1610101D01*
X3123418Y1610684D01*
X3124946Y1610101D01*
X3126038Y1608935D01*
X3126693Y1607476D01*
Y1599018D01*
G01Y1607476D02*
X3127348Y1608935D01*
X3128439Y1610101D01*
X3129968Y1610684D01*
X3131496Y1610101D01*
X3132588Y1608935D01*
X3133243Y1607185D01*
Y1599018D01*
G01X3140263Y1593185D02*
Y1610684D01*
G01Y1608060D02*
X3141355Y1609518D01*
X3142446Y1610393D01*
X3144193Y1610684D01*
X3145721Y1610393D01*
X3147250Y1608935D01*
X3147905Y1606893D01*
X3148123Y1604851D01*
X3147905Y1602809D01*
X3147250Y1600768D01*
X3145939Y1599601D01*
X3144193Y1599018D01*
X3142665Y1599310D01*
X3141136Y1600184D01*
X3140263Y1601351D01*
G01X3158418Y1606893D02*
X3165405D01*
X3164750Y1608935D01*
X3163658Y1610101D01*
X3162130Y1610684D01*
X3160601Y1610393D01*
X3159291Y1609518D01*
X3158418Y1607476D01*
X3157981Y1605726D01*
Y1603976D01*
X3158418Y1602226D01*
X3159510Y1600476D01*
X3160820Y1599310D01*
X3162348Y1599018D01*
X3163876Y1599601D01*
X3165405Y1601351D01*
G01X3183123Y1616518D02*
Y1599018D01*
G01Y1601642D02*
X3182250Y1600184D01*
X3180939Y1599310D01*
X3179411Y1599018D01*
X3177665Y1599601D01*
X3176355Y1601059D01*
X3175481Y1602809D01*
X3175263Y1604851D01*
X3175481Y1606893D01*
X3176355Y1608643D01*
X3177665Y1610101D01*
X3179411Y1610684D01*
X3180939Y1610393D01*
X3182031Y1609809D01*
X3183123Y1608643D01*
G01X3200623Y1599018D02*
Y1610684D01*
G01Y1608643D02*
X3199750Y1609809D01*
X3198439Y1610393D01*
X3196911Y1610684D01*
X3195383Y1610101D01*
X3194073Y1608935D01*
X3193199Y1607185D01*
X3192763Y1604851D01*
X3193199Y1602518D01*
X3194073Y1600768D01*
X3195383Y1599601D01*
X3196911Y1599018D01*
X3198439Y1599310D01*
X3199750Y1600184D01*
X3200623Y1601351D01*
G01X3210481Y1599018D02*
Y1610684D01*
G01Y1607768D02*
X3211355Y1609226D01*
X3212665Y1610393D01*
X3214411Y1610684D01*
X3215939Y1610393D01*
X3217250Y1609226D01*
X3217905Y1607185D01*
Y1599018D01*
G01X3235186Y1609226D02*
X3233658Y1610393D01*
X3232348Y1610684D01*
X3230601Y1610101D01*
X3229291Y1608935D01*
X3228418Y1606893D01*
X3228199Y1604851D01*
X3228418Y1602809D01*
X3229291Y1601059D01*
X3230601Y1599601D01*
X3232348Y1599018D01*
X3233876Y1599601D01*
X3235186Y1600768D01*
G01X3245918Y1606893D02*
X3252905D01*
X3252250Y1608935D01*
X3251158Y1610101D01*
X3249630Y1610684D01*
X3248101Y1610393D01*
X3246791Y1609518D01*
X3245918Y1607476D01*
X3245481Y1605726D01*
Y1603976D01*
X3245918Y1602226D01*
X3247010Y1600476D01*
X3248320Y1599310D01*
X3249848Y1599018D01*
X3251376Y1599601D01*
X3252905Y1601351D01*
G01X0Y-137756D02*
G03X15000Y-152756I15000J0D01*
G01X0Y-137756D02*
G03X15000Y-152756I15000J0D01*
G01X0Y-11811D02*
Y-137756D01*
G01Y-11811D02*
Y-137756D01*
G01X854331Y-152756D02*
X15000D01*
G01X854331D02*
X15000D01*
G01X23622Y-7874D02*
G03Y0I0J3937D01*
G01Y-7874D02*
G03Y0I0J3937D01*
G01X0Y3937D02*
G03X3937Y0I3937J0D01*
G01Y-7874D02*
X23622D01*
G01X0Y3937D02*
G03X3937Y0I3937J0D01*
G01Y-7874D02*
X23622D01*
G01X3937D02*
G03X0Y-11811I0J-3937D01*
G01X3937Y-7874D02*
G03X0Y-11811I0J-3937D01*
G01X3937Y0D02*
X397638D01*
G01X3937D02*
X397638D01*
G01X0Y1370866D02*
Y3937D01*
G01Y1370866D02*
Y3937D01*
G01X3937Y1374803D02*
G03X0Y1370866I0J-3937D01*
G01X3937Y1374803D02*
G03X0Y1370866I0J-3937D01*
G01X23622Y1374803D02*
G03Y1382677I0J3937D01*
G01Y1374803D02*
G03Y1382677I0J3937D01*
G01X3937D02*
X23622D01*
G01X0Y1386614D02*
G03X3937Y1382677I3937J0D01*
G01D02*
X23622D01*
G01X0Y1386614D02*
G03X3937Y1382677I3937J0D01*
G01Y1374803D02*
X746850D01*
G01D02*
X3937D01*
G01X0Y1386614D02*
Y1643268D01*
G01Y1386614D02*
Y1643268D01*
G01X15000Y1658268D02*
G03X0Y1643268I0J-15000D01*
G01X15000Y1658268D02*
G03X0Y1643268I0J-15000D01*
G01X775591Y1658268D02*
X15000D01*
G01X775591D02*
X15000D01*
G01X54331Y-7874D02*
X323228D01*
G01X54331D02*
X323228D01*
G01X54331Y0D02*
G03Y-7874I0J-3937D01*
G01Y0D02*
G03Y-7874I0J-3937D01*
G01Y1382677D02*
G03Y1374803I0J-3937D01*
G01Y1382677D02*
G03Y1374803I0J-3937D01*
G01Y1382677D02*
X353740D01*
G01X54331D02*
X353740D01*
G01X114295Y378885D02*
G03X148106I16905J-13531D01*
G01X114295D02*
G03X148106I16905J-13531D01*
G01X114295D02*
G03X121220Y392016I-30737J24602D01*
G01X114295Y378885D02*
G03X121220Y392016I-30737J24602D01*
G01X114295Y831641D02*
G03X121220Y844772I-30737J24601D01*
G01X114295Y831641D02*
G03X121220Y844772I-30737J24602D01*
G01X114295Y831641D02*
G03X148106I16905J-13531D01*
G01X114295D02*
G03X148106I16905J-13531D01*
G01X114295Y1284397D02*
G03X148106I16905J-13531D01*
G01X114295D02*
G03X148106I16905J-13531D01*
G01X114295D02*
G03X121220Y1297528I-30737J24601D01*
G01X114295Y1284397D02*
G03X121220Y1297528I-30737J24602D01*
G01X141181Y392016D02*
G03X121220I-9980J-3039D01*
G01X141181D02*
G03X148106Y378885I37662J11471D01*
G01X141181Y392016D02*
G03X121220I-9980J-3039D01*
G01X141181D02*
G03X148106Y378885I37662J11471D01*
G01X141181Y844772D02*
G03X148106Y831641I37662J11471D01*
G01X141181Y844772D02*
G03X148106Y831641I37662J11471D01*
G01X141181Y844772D02*
G03X121220I-9980J-3040D01*
G01X141181D02*
G03X121220I-9980J-3039D01*
G01X141181Y1297528D02*
G03X121220I-9980J-3040D01*
G01X141181D02*
G03X148106Y1284397I37662J11471D01*
G01X141181Y1297528D02*
G03X121220I-9980J-3040D01*
G01X141181D02*
G03X148106Y1284397I37662J11471D01*
G01X323228Y-7874D02*
G03Y0I0J3937D01*
G01Y-7874D02*
G03Y0I0J3937D01*
G01X362598D02*
G03Y-7874I0J-3937D01*
G01Y0D02*
G03Y-7874I0J-3937D01*
G01X362327Y378885D02*
G03X396138I16905J-13531D01*
G01X362327D02*
G03X396138I16905J-13531D01*
G01X362327D02*
G03X369252Y392016I-30737J24602D01*
G01X362327Y378885D02*
G03X369252Y392016I-30737J24602D01*
G01X362327Y831641D02*
G03X369252Y844772I-30737J24602D01*
G01X362327Y831641D02*
G03X369252Y844772I-30737J24602D01*
G01X362327Y831641D02*
G03X396138I16905J-13531D01*
G01X362327D02*
G03X396138I16905J-13531D01*
G01X362327Y1284397D02*
G03X396138I16905J-13531D01*
G01X362327D02*
G03X396138I16905J-13531D01*
G01X362327D02*
G03X369252Y1297528I-30737J24602D01*
G01X362327Y1284397D02*
G03X369252Y1297528I-30737J24602D01*
G01X353740Y1374803D02*
G03Y1382677I0J3937D01*
G01Y1374803D02*
G03Y1382677I0J3937D01*
G01X401575Y3937D02*
Y55118D01*
G01X397638Y0D02*
G03X401575Y3937I0J3937D01*
G01X409449D02*
Y51181D01*
G01X397638Y-7874D02*
G03X409449Y3937I0J11811D01*
G01X397638Y0D02*
G03X401575Y3937I0J3937D01*
G01D02*
Y55118D01*
G01X409449Y3937D02*
Y51181D01*
G01X397638Y-7874D02*
G03X409449Y3937I0J11811D01*
G01X362598Y-7874D02*
X397638D01*
G01X362598D02*
X397638D01*
G01X405512Y59055D02*
G03X401575Y55118I0J-3937D01*
G01X405512Y59055D02*
G03X401575Y55118I0J-3937D01*
G01X405512Y59055D02*
X586614D01*
G01X409449Y51181D02*
X582677D01*
G01X405512Y59055D02*
X586614D01*
G01X409449Y51181D02*
X582677D01*
G01X389213Y392016D02*
G03X396138Y378885I37662J11471D01*
G01X389213Y392016D02*
G03X396138Y378885I37662J11471D01*
G01X389213Y392016D02*
G03X369252I-9981J-3039D01*
G01X389213D02*
G03X369252I-9981J-3039D01*
G01X389213Y844772D02*
G03X396138Y831641I37662J11471D01*
G01X389213Y844772D02*
G03X396138Y831641I37662J11471D01*
G01X389213Y844772D02*
G03X369252I-9981J-3040D01*
G01X389213D02*
G03X369252I-9981J-3039D01*
G01X389213Y1297528D02*
G03X396138Y1284397I37662J11471D01*
G01X389213Y1297528D02*
G03X396138Y1284397I37662J11471D01*
G01X389213Y1297528D02*
G03X369252I-9981J-3040D01*
G01X389213D02*
G03X369252I-9981J-3040D01*
G01X393110Y1382677D02*
G03Y1374803I0J-3937D01*
G01Y1382677D02*
X692520D01*
G01X393110D02*
X692520D01*
G01X393110D02*
G03Y1374803I0J-3937D01*
G01X523327Y829921D02*
G03X483169I-20079J0D01*
G01X523327D02*
G03I-20079J0D01*
G01X483169D02*
G03X523327I20079J0D01*
G01X594488Y-7874D02*
X628765D01*
G01X594488D02*
X628765D01*
G01X590551Y55118D02*
Y3937D01*
G01D02*
G03X594488Y0I3937J0D01*
G01X582677Y51181D02*
Y3937D01*
G01D02*
G03X594488Y-7874I11811J0D01*
G01X590551Y55118D02*
Y3937D01*
G01D02*
G03X594488Y0I3937J0D01*
G01X582677Y51181D02*
Y3937D01*
G01D02*
G03X594488Y-7874I11811J0D01*
G01Y0D02*
X783465D01*
G01X594488D02*
X783465D01*
G01X590551Y55118D02*
G03X586614Y59055I-3937J0D01*
G01X590551Y55118D02*
G03X586614Y59055I-3937J0D01*
G01X628765Y-7874D02*
G03Y0I0J3937D01*
G01Y-7874D02*
G03Y0I0J3937D01*
G01X610358Y378885D02*
G03X644169I16906J-13531D01*
G01X610358D02*
G03X644169I16906J-13531D01*
G01X637244Y392016D02*
G03X644169Y378885I37662J11471D01*
G01X637244Y392016D02*
G03X644169Y378885I37662J11471D01*
G01X637244Y392016D02*
G03X617283I-9980J-3039D01*
G01X637244D02*
G03X617283I-9980J-3039D01*
G01X610358Y378885D02*
G03X617283Y392016I-30737J24602D01*
G01X610358Y378885D02*
G03X617283Y392016I-30737J24602D01*
G01X637244Y844772D02*
G03X644169Y831641I37662J11471D01*
G01X637244Y844772D02*
G03X644169Y831641I37662J11471D01*
G01X610358D02*
G03X617283Y844772I-30737J24601D01*
G01X610358Y831641D02*
G03X617283Y844772I-30737J24602D01*
G01X610358Y831641D02*
G03X644169I16906J-13531D01*
G01X610358D02*
G03X644169I16906J-13531D01*
G01X637244Y844772D02*
G03X617283I-9980J-3040D01*
G01X637244D02*
G03X617283I-9980J-3039D01*
G01X610358Y1284397D02*
G03X644169I16906J-13531D01*
G01X610358D02*
G03X644169I16906J-13531D01*
G01X637244Y1297528D02*
G03X644169Y1284397I37662J11471D01*
G01X637244Y1297528D02*
G03X644169Y1284397I37662J11471D01*
G01X610358D02*
G03X617283Y1297528I-30737J24601D01*
G01X637244D02*
G03X617283I-9980J-3040D01*
G01X610358Y1284397D02*
G03X617283Y1297528I-30737J24602D01*
G01X637244D02*
G03X617283I-9980J-3040D01*
G01X659474Y0D02*
G03Y-7874I0J-3937D01*
G01Y0D02*
G03Y-7874I0J-3937D01*
G01D02*
X780203D01*
G01X659474D02*
X780203D01*
G01X692520Y1374803D02*
G03Y1382677I0J3937D01*
G01Y1374803D02*
G03Y1382677I0J3937D01*
G01X746850Y1374803D02*
G03X750787Y1378740I0J3937D01*
G01X746850Y1374803D02*
G03X750787Y1378740I0J3937D01*
G01X723228Y1382677D02*
G03Y1374803I0J-3937D01*
G01Y1382677D02*
X742913D01*
G01X723228D02*
X742913D01*
G01X723228D02*
G03Y1374803I0J-3937D01*
G01X742913Y1464567D02*
Y1382677D01*
G01Y1464567D02*
Y1382677D01*
G01X754724Y1476378D02*
G03X742913Y1464567I0J-11811D01*
G01X754724Y1476378D02*
G03X742913Y1464567I0J-11811D01*
G01X862205Y-7874D02*
X791339D01*
G01X787402Y-3937D02*
G03X791339Y-7874I3937J0D01*
G01X787402Y-3937D02*
G03X791339Y-7874I3937J0D01*
G01D02*
X862205D01*
G01X858268Y-15748D02*
X791339D01*
G01X858268D02*
X791339D01*
G01X787402Y-3937D02*
G03X783465Y0I-3937J0D01*
G01X787402Y-3937D02*
G03X783465Y0I-3937J0D01*
G01X780203Y-7874D02*
G03X791339Y-15748I11136J3937D01*
G01X780203Y-7874D02*
G03X791339Y-15748I11136J3937D01*
G01X779551Y264712D02*
G03X813362I16905J-13531D01*
G01X779551D02*
G03X813362I16905J-13531D01*
G01X779551D02*
G03X786476Y277843I-30737J24601D01*
G01X806437D02*
G03X786476I-9981J-3040D01*
G01X779551Y264712D02*
G03X786476Y277843I-30737J24602D01*
G01X806437D02*
G03X786476I-9981J-3040D01*
G01X779551Y737153D02*
G03X786476Y750284I-30737J24601D01*
G01X779551Y737154D02*
G03X786476Y750284I-30736J24602D01*
G01X779551Y737153D02*
G03X813362I16905J-13531D01*
G01X779551D02*
G03X813362I16905J-13531D01*
G01X806437Y750284D02*
G03X786476I-9981J-3040D01*
G01X806437D02*
G03X786476I-9981J-3040D01*
G01X750787Y1464567D02*
Y1378740D01*
G01Y1464567D02*
Y1378740D01*
G01X783465Y1468504D02*
G03X787402Y1472441I0J3937D01*
G01X783465Y1468504D02*
G03X787402Y1472441I0J3937D01*
G01X783465Y1468504D02*
X754724D01*
G01D02*
G03X750787Y1464567I0J-3937D01*
G01X783465Y1468504D02*
X754724D01*
G01D02*
G03X750787Y1464567I0J-3937D01*
G01X779528Y1476378D02*
X754724D01*
G01X779528D02*
X754724D01*
G01X787402Y1654331D02*
Y1472441D01*
G01X779528Y1596063D02*
Y1476378D01*
G01X787402Y1654331D02*
Y1472441D01*
G01X779528Y1596063D02*
Y1476378D01*
G01X787402Y1596063D02*
G03X779528I-3937J0D01*
G01X787402D02*
G03X779528I-3937J0D01*
G01X1216535Y1658268D02*
X791339D01*
G01D02*
G03X787402Y1654331I0J-3937D01*
G01X779528D02*
G03X775591Y1658268I-3937J0D01*
G01X1216535D02*
X791339D01*
G01D02*
G03X787402Y1654331I0J-3937D01*
G01X779528D02*
G03X775591Y1658268I-3937J0D01*
G01X779528Y1654331D02*
Y1626772D01*
G01D02*
G03X787402I3937J0D01*
G01X779528Y1654331D02*
Y1626772D01*
G01D02*
G03X787402I3937J0D01*
G01X806437Y277843D02*
G03X813362Y264712I37662J11471D01*
G01X806437Y277843D02*
G03X813362Y264712I37662J11471D01*
G01X806437Y750284D02*
G03X813362Y737153I37662J11471D01*
G01X806437Y750284D02*
G03X813362Y737154I37661J11472D01*
G01X866142Y-148819D02*
Y-11811D01*
G01Y-148819D02*
G03X870079Y-152756I3937J0D01*
G01X866142Y-11811D02*
Y-148819D01*
G01D02*
G03X870079Y-152756I3937J0D01*
G01X866142Y-129134D02*
G03X858268I-3937J0D01*
G01X866142D02*
G03X858268I-3937J0D01*
G01Y-148819D02*
Y-129134D01*
G01X854331Y-152756D02*
G03X858268Y-148819I0J3937D01*
G01D02*
Y-129134D01*
G01X854331Y-152756D02*
G03X858268Y-148819I0J3937D01*
G01X1177165Y-152756D02*
X870079D01*
G01D02*
X1177165D01*
G01X858268Y-98425D02*
Y-15748D01*
G01Y-98425D02*
Y-15748D01*
G01Y-98425D02*
G03X866142I3937J0D01*
G01X858268D02*
G03X866142I3937J0D01*
G01Y-11811D02*
G03X862205Y-7874I-3937J0D01*
G01X866142Y-11811D02*
G03X862205Y-7874I-3937J0D01*
G01X927032Y-57820D02*
G03X962731I17850J-12259D01*
G01X927032Y-57821D02*
G03X962732I17850J-12258D01*
G01X927032Y-57820D02*
G03X935199Y-42571I-64908J44575D01*
G01X954565D02*
G03X935199I-9683J-3885D01*
G01X927032Y-57821D02*
G03X935199Y-42571I-64909J44573D01*
G01X954564D02*
G03X935199I-9682J-3885D01*
G01X944512Y1089122D02*
G03X978323I16905J-13531D01*
G01X944512Y1089121D02*
G03X978323I16905J-13531D01*
G01X944512Y1431641D02*
G03X978323I16905J-13531D01*
G01X944512D02*
G03X978323I16905J-13531D01*
G01X954565Y-42571D02*
G03X962731Y-57820I73077J29322D01*
G01X954564Y-42570D02*
G03X962732Y-57821I73076J29324D01*
G01X971398Y1102252D02*
G03X978323Y1089122I37661J11472D01*
G01X971398Y1102252D02*
G03X978323Y1089121I37662J11471D01*
G01X971398Y1102252D02*
G03X951437I-9980J-3039D01*
G01X971398D02*
G03X951437I-9980J-3039D01*
G01X944512Y1089122D02*
G03X951437Y1102252I-30737J24602D01*
G01X944512Y1089121D02*
G03X951437Y1102252I-30737J24602D01*
G01X971398Y1444772D02*
G03X978323Y1431641I37662J11471D01*
G01X971398Y1444772D02*
G03X978323Y1431641I37662J11471D01*
G01X971398Y1444772D02*
G03X951437I-9980J-3040D01*
G01X944512Y1431641D02*
G03X951437Y1444772I-30737J24602D01*
G01X944512Y1431641D02*
G03X951437Y1444772I-30737J24602D01*
G01X971398D02*
G03X951437I-9980J-3039D01*
G01X1181102Y-148819D02*
Y-3937D01*
G01X1177165Y-152756D02*
G03X1181102Y-148819I0J3937D01*
G01X1177165Y-152756D02*
G03X1181102Y-148819I0J3937D01*
G01D02*
Y-3937D01*
G01Y-94488D02*
G03X1188976I3937J0D01*
G01X1181102D02*
G03X1188976I3937J0D01*
G01Y-125197D02*
G03X1181102I-3937J0D01*
G01X1188976D02*
G03X1181102I-3937J0D01*
G01X1185039Y0D02*
G03X1181102Y-3937I0J-3937D01*
G01X1185039Y0D02*
G03X1181102Y-3937I0J-3937D01*
G01X1164984Y557626D02*
G03X1198795I16906J-13531D01*
G01X1164984Y557625D02*
G03X1198795I16906J-13531D01*
G01X1191870Y570756D02*
G03X1171909I-9980J-3039D01*
G01X1191870D02*
G03X1171909I-9980J-3039D01*
G01X1164984Y557626D02*
G03X1171909Y570756I-30736J24602D01*
G01X1164984Y557625D02*
G03X1171909Y570756I-30737J24602D01*
G01X1164984Y971011D02*
G03X1198795I16906J-13531D01*
G01X1164984D02*
G03X1198795I16906J-13531D01*
G01X1191870Y984142D02*
G03X1171909I-9980J-3040D01*
G01X1191870D02*
G03X1171909I-9980J-3039D01*
G01X1164984Y971011D02*
G03X1171909Y984142I-30737J24602D01*
G01X1164984Y971011D02*
G03X1171909Y984142I-30737J24602D01*
G01X1164173Y1378740D02*
Y1468504D01*
G01X1930906Y1374803D02*
X1168110D01*
G01X1164173Y1378740D02*
G03X1168110Y1374803I3937J0D01*
G01X1172047Y1382677D02*
Y1464567D01*
G01X1195669Y1382677D02*
X1172047D01*
G01X1930906Y1374803D02*
X1168110D01*
G01X1164173Y1378740D02*
G03X1168110Y1374804I3937J1D01*
G01X1164173Y1378740D02*
Y1468504D01*
G01X1172047Y1382677D02*
Y1464567D01*
G01X1195669Y1382677D02*
X1172047D01*
G01X1168110Y1472441D02*
G03X1164173Y1468504I0J-3937D01*
G01X1168110Y1472441D02*
G03X1164173Y1468504I0J-3937D01*
G01X1172047Y1464567D02*
X1216535D01*
G01X1172047D02*
X1216535D01*
G01X1168110Y1472441D02*
X1216535D01*
G01X1168110D02*
X1216535D01*
G01X1164984Y1561563D02*
G03X1171909Y1574693I-30736J24602D01*
G01X1164984Y1561562D02*
G03X1171909Y1574693I-30737J24602D01*
G01X1164984Y1561563D02*
G03X1198795I16906J-13531D01*
G01X1164984Y1561562D02*
G03X1198795I16906J-13531D01*
G01X1191870Y1574693D02*
G03X1171909I-9980J-3039D01*
G01X1191870D02*
G03X1171909I-9980J-3039D01*
G01X1188976Y-148819D02*
Y-125197D01*
G01Y-148819D02*
G03X1192913Y-152756I3937J0D01*
G01X1188976Y-148819D02*
Y-125197D01*
G01Y-148819D02*
G03X1192913Y-152756I3937J0D01*
G01D02*
X1919843D01*
G01X1192913D02*
X1919843D01*
G01X1188976Y-94488D02*
Y-7874D01*
G01Y-94488D02*
Y-7874D01*
G01X1185039Y0D02*
X1366142D01*
G01X1188976Y-7874D02*
X1315748D01*
G01X1185039Y0D02*
X1366142D01*
G01X1188976Y-7874D02*
X1315748D01*
G01X1191870Y570756D02*
G03X1198795Y557626I37662J11472D01*
G01X1191870Y570756D02*
G03X1198795Y557626I37662J11472D01*
G01X1191870Y984142D02*
G03X1198795Y971011I37662J11471D01*
G01X1191870Y984142D02*
G03X1198795Y971011I37662J11471D01*
G01X1524606Y1382677D02*
X1226378D01*
G01X1524606D02*
X1226378D01*
G01X1195669Y1374803D02*
G03Y1382677I0J3937D01*
G01X1226378D02*
G03Y1374803I0J-3937D01*
G01X1195669D02*
G03Y1382677I0J3937D01*
G01X1226378D02*
G03Y1374803I0J-3937D01*
G01X1216535Y1464567D02*
G03X1228346Y1476378I0J11811D01*
G01X1216535Y1464567D02*
G03X1228346Y1476378I0J11811D01*
G01Y1592126D02*
Y1476378D01*
G01Y1592126D02*
Y1476378D01*
G01X1220472Y1654331D02*
Y1476378D01*
G01X1216535Y1472441D02*
G03X1220472Y1476378I0J3937D01*
G01X1216535Y1472441D02*
G03X1220472Y1476378I0J3937D01*
G01D02*
Y1654331D01*
G01X1191870Y1574693D02*
G03X1198795Y1561563I37662J11472D01*
G01X1191870Y1574693D02*
G03X1198795Y1561562I37662J11471D01*
G01X1228346Y1592126D02*
G03X1220472I-3937J0D01*
G01X1228346D02*
G03X1220472I-3937J0D01*
G01X1232283Y1658268D02*
X1442382D01*
G01X1232283D02*
G03X1228346Y1654331I0J-3937D01*
G01X1232283Y1658268D02*
X1442382D01*
G01X1232283D02*
G03X1228346Y1654331I0J-3937D01*
G01D02*
Y1622835D01*
G01Y1654331D02*
Y1622835D01*
G01X1220472Y1654331D02*
G03X1216535Y1658268I-3937J0D01*
G01X1220472Y1654331D02*
G03X1216535Y1658268I-3937J0D01*
G01X1220472Y1622835D02*
G03X1228346I3937J0D01*
G01X1220472D02*
G03X1228346I3937J0D01*
G01X1284965Y378885D02*
G03X1318776I16906J-13531D01*
G01X1284965D02*
G03X1318775I16905J-13531D01*
G01X1284965Y831641D02*
G03X1318776I16906J-13531D01*
G01X1284965D02*
G03X1318775I16905J-13531D01*
G01X1284965Y1284397D02*
G03X1318776I16906J-13531D01*
G01X1284965D02*
G03X1318775I16905J-13531D01*
G01X1315748Y-7874D02*
G03Y0I0J3937D01*
G01Y-7874D02*
G03Y0I0J3937D01*
G01X1311850Y392016D02*
G03X1291890I-9980J-3040D01*
G01X1311850D02*
G03X1318776Y378885I37662J11473D01*
G01X1311851Y392016D02*
G03X1291890I-9980J-3039D01*
G01X1311851D02*
G03X1318775Y378885I37663J11469D01*
G01X1284965D02*
G03X1291890Y392016I-30737J24602D01*
G01X1284965Y378885D02*
G03X1291890Y392016I-30737J24602D01*
G01X1284965Y831641D02*
G03X1291890Y844772I-30737J24602D01*
G01X1311850D02*
G03X1318776Y831641I37662J11473D01*
G01X1284965D02*
G03X1291890Y844772I-30737J24602D01*
G01X1311851D02*
G03X1318775Y831641I37663J11469D01*
G01X1311850Y844772D02*
G03X1291890I-9980J-3040D01*
G01X1311851D02*
G03X1291890I-9980J-3039D01*
G01X1284965Y1284397D02*
G03X1291890Y1297528I-30737J24602D01*
G01X1311850D02*
G03X1291890I-9980J-3040D01*
G01X1311850D02*
G03X1318776Y1284397I37661J11473D01*
G01X1284965D02*
G03X1291890Y1297528I-30737J24602D01*
G01X1311851D02*
G03X1291890I-9980J-3040D01*
G01X1311851D02*
G03X1318775Y1284397I37663J11469D01*
G01X1377953Y3937D02*
Y51181D01*
G01Y3937D02*
Y51181D01*
G01X1370079Y3937D02*
Y55118D01*
G01X1366142Y0D02*
G03X1370079Y3937I0J3937D01*
G01X1366142Y-7874D02*
G03X1377953Y3937I0J11811D01*
G01X1346457Y-7874D02*
X1366142D01*
G01Y0D02*
G03X1370079Y3937I0J3937D01*
G01D02*
Y55118D01*
G01X1346457Y-7874D02*
X1366142D01*
G01D02*
G03X1377953Y3937I0J11811D01*
G01X1346457Y0D02*
G03Y-7874I0J-3937D01*
G01Y0D02*
G03Y-7874I0J-3937D01*
G01X1374016Y59055D02*
G03X1370079Y55118I0J-3937D01*
G01X1374016Y59056D02*
G03X1370079Y55118I0J-3937D01*
G01X1374016Y59055D02*
X1555118D01*
G01X1377953Y51181D02*
X1551181D01*
G01X1374016Y59055D02*
X1555118D01*
G01X1377953Y51181D02*
X1551181D01*
G01X1442382Y1658268D02*
G03X1450256I3937J0D01*
G01X1442382D02*
G03X1450256I3937J0D01*
G01D02*
X1919843D01*
G01X1450256D02*
X1919843D01*
G01X1562992Y0D02*
X1930906D01*
G01X1559055Y55118D02*
Y3937D01*
G01D02*
G03X1562992Y0I3937J0D01*
G01Y-7874D02*
X1593701D01*
G01X1559055Y55118D02*
Y3937D01*
G01D02*
G03X1562992Y0I3937J0D01*
G01D02*
X1930906D01*
G01X1562992Y-7874D02*
X1593701D01*
G01X1551181Y51181D02*
Y3937D01*
G01D02*
G03X1562992Y-7874I11811J0D01*
G01X1551181Y51181D02*
Y3937D01*
G01D02*
G03X1562992Y-7874I11811J0D01*
G01X1559055Y55118D02*
G03X1555118Y59055I-3937J0D01*
G01X1559055Y55118D02*
G03X1555118Y59055I-3937J0D01*
G01X1532996Y378885D02*
G03X1566807I16906J-13531D01*
G01X1532996D02*
G03X1566807I16906J-13531D01*
G01X1559882Y392016D02*
G03X1566807Y378885I37662J11471D01*
G01X1559882Y392016D02*
G03X1566807Y378885I37662J11471D01*
G01X1559882Y392016D02*
G03X1539921I-9980J-3039D01*
G01X1559882D02*
G03X1539921I-9980J-3039D01*
G01X1532996Y378885D02*
G03X1539921Y392016I-30737J24602D01*
G01X1532996Y378885D02*
G03X1539921Y392016I-30737J24602D01*
G01X1559882Y844772D02*
G03X1566807Y831641I37662J11471D01*
G01X1559882Y844772D02*
G03X1566807Y831641I37662J11471D01*
G01X1532996D02*
G03X1539921Y844772I-30737J24602D01*
G01X1532996Y831641D02*
G03X1539921Y844772I-30737J24602D01*
G01X1532996Y831641D02*
G03X1566807I16906J-13531D01*
G01X1532996D02*
G03X1566807I16906J-13531D01*
G01X1559882Y844772D02*
G03X1539921I-9980J-3040D01*
G01X1559882D02*
G03X1539921I-9980J-3039D01*
G01X1532996Y1284397D02*
G03X1566807I16906J-13531D01*
G01X1532996D02*
G03X1566807I16906J-13531D01*
G01X1559882Y1297528D02*
G03X1566807Y1284397I37662J11471D01*
G01X1559882Y1297528D02*
G03X1566807Y1284397I37662J11471D01*
G01X1559882Y1297528D02*
G03X1539921I-9980J-3040D01*
G01X1532996Y1284397D02*
G03X1539921Y1297528I-30737J24602D01*
G01X1532996Y1284397D02*
G03X1539921Y1297528I-30737J24602D01*
G01X1559882D02*
G03X1539921I-9980J-3040D01*
G01X1563976Y1382677D02*
G03Y1374803I0J-3937D01*
G01Y1382677D02*
G03Y1374803I0J-3937D01*
G01X1524606D02*
G03Y1382677I0J3937D01*
G01Y1374803D02*
G03Y1382677I0J3937D01*
G01X1864567D02*
X1563976D01*
G01X1864567D02*
X1563976D01*
G01X1593701Y-7874D02*
G03Y0I0J3937D01*
G01Y-7874D02*
G03Y0I0J3937D01*
G01X1633071D02*
G03Y-7874I0J-3937D01*
G01D02*
X1880512D01*
G01X1633071D02*
X1880512D01*
G01X1633071Y0D02*
G03Y-7874I0J-3937D01*
G01X1693996Y829921D02*
G03X1653839I-20078J0D01*
G01X1693996D02*
G03I-20079J0D01*
G01X1653839D02*
G03X1693996I20078J0D01*
G01X1781028Y378885D02*
G03X1814839I16906J-13531D01*
G01X1781028D02*
G03X1814838I16905J-13531D01*
G01X1807913Y392016D02*
G03X1814839Y378885I37662J11473D01*
G01X1807914Y392016D02*
G03X1814838Y378885I37663J11469D01*
G01X1807913Y392016D02*
G03X1787953I-9980J-3040D01*
G01X1807914D02*
G03X1787953I-9980J-3039D01*
G01X1781028Y378885D02*
G03X1787953Y392016I-30737J24602D01*
G01X1781028Y378885D02*
G03X1787953Y392016I-30737J24602D01*
G01X1807913Y844772D02*
G03X1814839Y831641I37662J11473D01*
G01X1807914Y844772D02*
G03X1814838Y831641I37663J11469D01*
G01X1781028D02*
G03X1787953Y844772I-30737J24602D01*
G01X1781028Y831641D02*
G03X1787953Y844772I-30737J24602D01*
G01X1781028Y831641D02*
G03X1814839I16906J-13531D01*
G01X1781028D02*
G03X1814838I16905J-13531D01*
G01X1807913Y844772D02*
G03X1787953I-9980J-3040D01*
G01X1807914D02*
G03X1787953I-9980J-3039D01*
G01X1781028Y1284397D02*
G03X1814839I16906J-13531D01*
G01X1781028D02*
G03X1814838I16905J-13531D01*
G01X1807913Y1297528D02*
G03X1814839Y1284397I37661J11473D01*
G01X1807914Y1297528D02*
G03X1814838Y1284397I37663J11469D01*
G01X1807913Y1297528D02*
G03X1787953I-9980J-3040D01*
G01X1781028Y1284397D02*
G03X1787953Y1297528I-30737J24602D01*
G01X1781028Y1284397D02*
G03X1787953Y1297528I-30737J24602D01*
G01X1807914D02*
G03X1787953I-9980J-3040D01*
G01X1911220Y0D02*
G03Y-7874I0J-3937D01*
G01Y0D02*
G03Y-7874I0J-3937D01*
G01X1880512D02*
G03Y0I0J3937D01*
G01Y-7874D02*
G03Y0I0J3937D01*
G01X1930906Y1382677D02*
X1895276D01*
G01D02*
G03Y1374803I0J-3937D01*
G01X1930906Y1382677D02*
X1895276D01*
G01D02*
G03Y1374803I0J-3937D01*
G01X1864567D02*
G03Y1382677I0J3937D01*
G01Y1374803D02*
G03Y1382677I0J3937D01*
G01X1919843Y-152756D02*
G03X1934843Y-137756I0J15000D01*
G01X1919843Y-152756D02*
G03X1934843Y-137756I0J15000D01*
G01Y-11811D02*
Y-137756D01*
G01Y-11811D02*
Y-137756D01*
G01X1930906Y0D02*
G03X1934843Y3937I0J3937D01*
G01X1930906Y0D02*
G03X1934843Y3937I0J3937D01*
G01Y-11811D02*
G03X1930906Y-7874I-3937J0D01*
G01X1934843Y-11811D02*
G03X1930906Y-7874I-3937J0D01*
G01X1911220D02*
X1930906D01*
G01X1911220D02*
X1930906D01*
G01X1934843Y1370866D02*
Y3937D01*
G01D02*
Y1370866D01*
G01D02*
G03X1930906Y1374803I-3937J0D01*
G01X1934843Y1370866D02*
G03X1930906Y1374803I-3937J0D01*
G01Y1382677D02*
G03X1934843Y1386614I0J3937D01*
G01X1930906Y1382677D02*
G03X1934843Y1386614I0J3937D01*
G01D02*
Y1643268D01*
G01Y1386614D02*
Y1643268D01*
G01D02*
G03X1919843Y1658268I-15000J0D01*
G01X1934843Y1643268D02*
G03X1919843Y1658268I-15000J0D01*
G54D12*
G01X555264Y523331D02*
X553279D01*
G01X569135Y509460D02*
X555264Y523331D01*
G01X580456Y528308D02*
X572229Y520081D01*
G01X580456Y546270D02*
Y528308D01*
G01X616341Y582155D02*
X580456Y546270D01*
G01X652926Y509460D02*
X569135D01*
G01X637213Y582155D02*
X616341D01*
G01X658646Y515180D02*
X652926Y509460D01*
G01X853200Y508500D02*
X839500D01*
G01X872750Y475050D02*
X874900D01*
G01X870185Y472485D02*
X872750Y475050D01*
G01X866100Y472485D02*
X870185D01*
G01X874900Y478000D02*
X873000Y479900D01*
G01X874900Y475050D02*
Y478000D01*
G01X872000Y480900D02*
X873000Y479900D01*
G01X872000Y484250D02*
Y480900D01*
G01Y489700D02*
X853200Y508500D01*
G01X872000Y487750D02*
Y489700D01*
G01X867362Y1341545D02*
X903539Y1305368D01*
G01X861444Y1338977D02*
X941841Y1258580D01*
G01X864444Y1340220D02*
X920552Y1284112D01*
G01X858444Y1337734D02*
X966081Y1230097D01*
G01X867362Y1433314D02*
Y1341545D01*
G01X861444Y1435882D02*
Y1338977D01*
G01X864444Y1434639D02*
Y1340220D01*
G01X858444Y1437125D02*
Y1337734D01*
G01X891800Y1384700D02*
Y1349965D01*
G01Y1346500D02*
Y1349965D01*
G01X896500Y1341800D02*
X891800Y1346500D01*
G01X886792Y1389708D02*
X891800Y1384700D01*
G01X886792Y1404100D02*
Y1389708D01*
G01X905991Y1471943D02*
X867362Y1433314D01*
G01X899991Y1474429D02*
X861444Y1435882D01*
G01X902991Y1473186D02*
X864444Y1434639D01*
G01X896991Y1475672D02*
X858444Y1437125D01*
G01X987698Y1221209D02*
X903539Y1305368D01*
G01X985213Y1215208D02*
X941841Y1258580D01*
G01X986456Y1218208D02*
X920552Y1284112D01*
G01X905991Y1499954D02*
Y1471943D01*
G01X927001Y1520964D02*
X905991Y1499954D01*
G01X899991Y1502441D02*
Y1474429D01*
G01X903504Y1505954D02*
X899991Y1502441D01*
G01X903505Y1505954D02*
X903504D01*
G01X921001Y1523450D02*
X903505Y1505954D01*
G01X902991Y1501198D02*
Y1473186D01*
G01X924001Y1522208D02*
X902991Y1501198D01*
G01X896991Y1503684D02*
Y1475672D01*
G01X902261Y1508954D02*
X896991Y1503684D01*
G01X902262Y1508954D02*
X902261D01*
G01X915451Y1522143D02*
X902262Y1508954D01*
G01X927001Y1549790D02*
Y1520964D01*
G01X924300Y1552491D02*
X927001Y1549790D01*
G01X924300Y1614320D02*
Y1552491D01*
G01X921001Y1547304D02*
Y1523450D01*
G01X917880Y1550425D02*
X921001Y1547304D01*
G01X917880Y1609460D02*
Y1550425D01*
G01X924001Y1548547D02*
Y1522208D01*
G01X921120Y1551428D02*
X924001Y1548547D01*
G01X921120Y1612740D02*
Y1551428D01*
G01X915451Y1548611D02*
Y1522143D01*
G01X914740Y1549322D02*
X915451Y1548611D01*
G01X914740Y1607040D02*
Y1549322D01*
G01X916179Y1622441D02*
X924300Y1614320D01*
G01X914741Y1612599D02*
X917880Y1609460D01*
G01X911811Y1612599D02*
X914741D01*
G01X901483Y1583235D02*
X911516Y1573202D01*
G01X901483Y1618083D02*
Y1583235D01*
G01X915749Y1618111D02*
X921120Y1612740D01*
G01X908570Y1579848D02*
X911616Y1576802D01*
G01X908570Y1612691D02*
Y1579848D01*
G01X904725Y1616536D02*
X908570Y1612691D01*
G01X913512Y1608268D02*
X914740Y1607040D01*
G01X911811Y1608268D02*
X913512D01*
G01X911811Y1622441D02*
X916179D01*
G01X904725Y1621325D02*
X901483Y1618083D01*
G01X904725Y1622048D02*
Y1621325D01*
G01X911811Y1618111D02*
X915749D01*
G01X917959Y1653800D02*
X924059Y1647700D01*
G01X910408Y1653800D02*
X917959D01*
G01X908000Y1651392D02*
X910408Y1653800D01*
G01X908000Y1648157D02*
Y1651392D01*
G01X904725Y1644882D02*
X908000Y1648157D01*
G01X1024809Y1221209D02*
X987698D01*
G01X990183Y1215208D02*
X985213D01*
G01X990184Y1215209D02*
X990183Y1215208D01*
G01X1022323Y1215209D02*
X990184D01*
G01X1023567Y1218208D02*
X986456D01*
G01X983970Y1212208D02*
X966081Y1230097D01*
G01X991426Y1212208D02*
X983970D01*
G01X1030079Y1215939D02*
X1024809Y1221209D01*
G01X1030079Y1215938D02*
Y1215939D01*
G01X1107758Y1138259D02*
X1030079Y1215938D01*
G01X1024079Y1213453D02*
X1022323Y1215209D01*
G01X1024079Y1213452D02*
Y1213453D01*
G01X1100765Y1136766D02*
X1024079Y1213452D01*
G01X1027079Y1214696D02*
X1023567Y1218208D01*
G01X1027079Y1214695D02*
Y1214696D01*
G01X1104137Y1137637D02*
X1027079Y1214695D01*
G01X991427Y1212209D02*
X991426Y1212208D01*
G01X1021079Y1212209D02*
X991427D01*
G01X1096394Y1136894D02*
X1021079Y1212209D01*
G01X1107758Y1122258D02*
Y1138259D01*
G01X1103064Y1117564D02*
X1107758Y1122258D01*
G01X1103064Y1113626D02*
Y1117564D01*
G01X1100765Y1123765D02*
Y1136766D01*
G01X1096460Y1119460D02*
X1100765Y1123765D01*
G01X1096460Y1115125D02*
Y1119460D01*
G01X1104137Y1123137D02*
Y1137637D01*
G01X1099020Y1118020D02*
X1104137Y1123137D01*
G01X1099020Y1112276D02*
Y1118020D01*
G01X1096394Y1122894D02*
Y1136894D01*
G01X1092742Y1119242D02*
X1096394Y1122894D01*
G01X1092742Y1113462D02*
Y1119242D01*
G01X1395300Y438500D02*
X1568500D01*
G01X1502400Y544100D02*
X1548021D01*
G01D02*
X1568500D01*
G01X1685047Y971153D02*
Y1014966D01*
G01X1694800Y961400D02*
X1685047Y971153D01*
G01X1729908Y961400D02*
X1694800D01*
G01X1733168Y958140D02*
X1729908Y961400D01*
G01X1760759Y958140D02*
X1733168D01*
G01X1768692Y966073D02*
X1760759Y958140D01*
M02*
